(kicad_pcb
	(version 20240108)
	(generator "pcbnew")
	(generator_version "8.0")
	(general
		(thickness 1.586)
		(legacy_teardrops no)
	)
	(paper "A4")
	(title_block
		(title "GMSL Serializer")
		(date "2024-11-27")
		(rev "1.1.1")
		(company "Antmicro Ltd")
		(comment 1 "www.antmicro.com")
		(comment 9 "footprints 39-43 of 117")
	)
	(layers
		(0 "F.Cu" signal)
		(1 "In1.Cu" power)
		(2 "In2.Cu" power)
		(31 "B.Cu" signal)
		(32 "B.Adhes" user "B.Adhesive")
		(33 "F.Adhes" user "F.Adhesive")
		(34 "B.Paste" user)
		(35 "F.Paste" user)
		(36 "B.SilkS" user "B.Silkscreen")
		(37 "F.SilkS" user "F.Silkscreen")
		(38 "B.Mask" user)
		(39 "F.Mask" user)
		(40 "Dwgs.User" user "User.Drawings")
		(41 "Cmts.User" user "User.Comments")
		(42 "Eco1.User" user "User.Eco1")
		(43 "Eco2.User" user "User.Eco2")
		(44 "Edge.Cuts" user)
		(45 "Margin" user)
		(46 "B.CrtYd" user "B.Courtyard")
		(47 "F.CrtYd" user "F.Courtyard")
		(48 "B.Fab" user)
		(49 "F.Fab" user)
	)
	(footprint "antmicro-footprints:R_0402_1005Metric"
		(layer "F.Cu")
		(at 143.82 115.57 90)
		(descr "Resistor SMD 0402")
		(tags "resistor SMD 0402")
		(property "Reference" "R46"
			(at 0.79 0.43 90)
			(layer "F.SilkS")
			(effects
				(font
					(size 0.7 0.7)
					(thickness 0.15)
				)
				(justify left bottom)
			)
		)
		(property "Value" "R_200R_0402"
			(at -1.011843 1.772047 90)
			(layer "F.Fab")
			(effects
				(font
					(size 0.7 0.7)
					(thickness 0.15)
				)
				(justify left bottom)
			)
		)
		(property "Footprint" "antmicro-footprints:R_0402_1005Metric"
			(at 0 0 90)
			(layer "F.Fab")
			(hide yes)
			(effects
				(font
					(size 1.27 1.27)
					(thickness 0.15)
				)
			)
		)
		(property "Datasheet" "https://www.bourns.com/docs/product-datasheets/cr.pdf"
			(at 0 0 90)
			(layer "F.Fab")
			(hide yes)
			(effects
				(font
					(size 1.27 1.27)
					(thickness 0.15)
				)
			)
		)
		(property "MPN" "CR0402-FX-2000GLF"
			(at 0 0 90)
			(unlocked yes)
			(layer "F.Fab")
			(hide yes)
			(effects
				(font
					(size 1 1)
					(thickness 0.15)
				)
			)
		)
		(property "Manufacturer" "Bourns"
			(at 0 0 90)
			(unlocked yes)
			(layer "F.Fab")
			(hide yes)
			(effects
				(font
					(size 1 1)
					(thickness 0.15)
				)
			)
		)
		(property "License" "Apache-2.0"
			(at 0 0 90)
			(unlocked yes)
			(layer "F.Fab")
			(hide yes)
			(effects
				(font
					(size 1 1)
					(thickness 0.15)
				)
			)
		)
		(property "Author" "Antmicro"
			(at 0 0 90)
			(unlocked yes)
			(layer "F.Fab")
			(hide yes)
			(effects
				(font
					(size 1 1)
					(thickness 0.15)
				)
			)
		)
		(property "Val" "200R"
			(at 0 0 90)
			(unlocked yes)
			(layer "F.Fab")
			(hide yes)
			(effects
				(font
					(size 1 1)
					(thickness 0.15)
				)
			)
		)
		(property "Tolerance" "1%"
			(at 0 0 90)
			(unlocked yes)
			(layer "F.Fab")
			(hide yes)
			(effects
				(font
					(size 1 1)
					(thickness 0.15)
				)
			)
		)
		(property "Public" ""
			(at 0 0 90)
			(unlocked yes)
			(layer "F.Fab")
			(hide yes)
			(effects
				(font
					(size 1 1)
					(thickness 0.15)
				)
			)
		)
		(sheetname "Supply")
		(sheetfile "supply.kicad_sch")
		(attr smd)
		(fp_rect
			(start -0.925 -0.47)
			(end 0.925 0.47)
			(stroke
				(width 0.05)
				(type default)
			)
			(fill none)
			(layer "F.CrtYd")
		)
		(fp_rect
			(start -0.5 -0.25)
			(end 0.5 0.25)
			(stroke
				(width 0.15)
				(type solid)
			)
			(fill none)
			(layer "F.Fab")
		)
		(fp_text user "${REFERENCE}"
			(at -0.95 3.168 90)
			(layer "F.Fab")
			(hide yes)
			(effects
				(font
					(size 0.7 0.7)
					(thickness 0.15)
				)
				(justify left bottom)
			)
		)
		(fp_text user "Author: Antmicro"
			(at -0.95 4.169 90)
			(layer "F.Fab")
			(hide yes)
			(effects
				(font
					(size 0.7 0.7)
					(thickness 0.15)
				)
				(justify left bottom)
			)
		)
		(fp_text user "License: Apache-2.0"
			(at -0.95 5.169 90)
			(layer "F.Fab")
			(hide yes)
			(effects
				(font
					(size 0.7 0.7)
					(thickness 0.15)
				)
				(justify left bottom)
			)
		)
		(pad "1" smd roundrect
			(at -0.48 0 90)
			(size 0.59 0.64)
			(layers "F.Cu" "F.Paste" "F.Mask")
			(roundrect_rratio 0.25)
			(net 1 "GND")
			(pintype "passive")
		)
		(pad "2" smd roundrect
			(at 0.48 0 90)
			(size 0.59 0.64)
			(layers "F.Cu" "F.Paste" "F.Mask")
			(roundrect_rratio 0.25)
			(net 95 "Net-(D11-C)")
			(pintype "passive")
		)
	)
	(footprint "antmicro-footprints:L_Coilcraft-MSS6132T"
		(layer "F.Cu")
		(at 161.6 89.662 180)
		(property "Reference" "L3"
			(at 0.65 -4.1 180)
			(layer "F.SilkS")
			(effects
				(font
					(size 0.7 0.7)
					(thickness 0.15)
				)
				(justify left bottom)
			)
		)
		(property "Value" "L_22u_1.12A_Coilcraft-MSS6132T"
			(at -0.508 4.826 180)
			(layer "F.Fab")
			(effects
				(font
					(size 0.7 0.7)
					(thickness 0.15)
				)
				(justify left bottom)
			)
		)
		(property "Footprint" "antmicro-footprints:L_Coilcraft-MSS6132T"
			(at 0 0 180)
			(layer "F.Fab")
			(hide yes)
			(effects
				(font
					(size 1.27 1.27)
					(thickness 0.15)
				)
			)
		)
		(property "Datasheet" "https://www.coilcraft.com/getmedia/d035c9b3-191d-46aa-ab3f-5c1a849157c1/mss6132t.pdf"
			(at 0 0 180)
			(layer "F.Fab")
			(hide yes)
			(effects
				(font
					(size 1.27 1.27)
					(thickness 0.15)
				)
			)
		)
		(property "Author" "Antmicro"
			(at 323.2 179.324 0)
			(layer "F.Fab")
			(hide yes)
			(effects
				(font
					(size 1 1)
					(thickness 0.15)
				)
			)
		)
		(property "IMax" "1.45A"
			(at 323.2 179.324 0)
			(layer "F.Fab")
			(hide yes)
			(effects
				(font
					(size 1 1)
					(thickness 0.15)
				)
			)
		)
		(property "ISat" "1.12A"
			(at 323.2 179.324 0)
			(layer "F.Fab")
			(hide yes)
			(effects
				(font
					(size 1 1)
					(thickness 0.15)
				)
			)
		)
		(property "License" "Apache-2.0"
			(at 323.2 179.324 0)
			(layer "F.Fab")
			(hide yes)
			(effects
				(font
					(size 1 1)
					(thickness 0.15)
				)
			)
		)
		(property "MPN" "MSS6132T-223"
			(at 323.2 179.324 0)
			(layer "F.Fab")
			(hide yes)
			(effects
				(font
					(size 1 1)
					(thickness 0.15)
				)
			)
		)
		(property "Manufacturer" "Coilcraft"
			(at 323.2 179.324 0)
			(layer "F.Fab")
			(hide yes)
			(effects
				(font
					(size 1 1)
					(thickness 0.15)
				)
			)
		)
		(property "Size" "6.1x6.1"
			(at 323.2 179.324 0)
			(layer "F.Fab")
			(hide yes)
			(effects
				(font
					(size 1 1)
					(thickness 0.15)
				)
			)
		)
		(property "Val" "22u/1.12A"
			(at 323.2 179.324 0)
			(layer "F.Fab")
			(hide yes)
			(effects
				(font
					(size 1 1)
					(thickness 0.15)
				)
			)
		)
		(sheetname "GMSL Connector")
		(sheetfile "GMSL.kicad_sch")
		(attr smd)
		(fp_line
			(start -0.8 3.05)
			(end 0.8 3.05)
			(stroke
				(width 0.15)
				(type solid)
			)
			(layer "F.SilkS")
		)
		(fp_line
			(start -0.8 -3.05)
			(end 0.8 -3.05)
			(stroke
				(width 0.15)
				(type solid)
			)
			(layer "F.SilkS")
		)
		(fp_rect
			(start -3.35 -3.35)
			(end 3.35 3.35)
			(stroke
				(width 0.05)
				(type solid)
			)
			(fill none)
			(layer "F.CrtYd")
		)
		(fp_rect
			(start -3.1 -3.1)
			(end 3.1 3.1)
			(stroke
				(width 0.15)
				(type solid)
			)
			(fill none)
			(layer "F.Fab")
		)
		(fp_text user "Author: Antmicro"
			(at -3.35 9.226 180)
			(layer "F.Fab")
			(hide yes)
			(effects
				(font
					(size 0.7 0.7)
					(thickness 0.15)
				)
				(justify left bottom)
			)
		)
		(fp_text user "License: Apache-2.0"
			(at -3.35 8.026 180)
			(layer "F.Fab")
			(hide yes)
			(effects
				(font
					(size 0.7 0.7)
					(thickness 0.15)
				)
				(justify left bottom)
			)
		)
		(fp_text user "${REFERENCE}"
			(at -3.35 6.826 180)
			(layer "F.Fab")
			(hide yes)
			(effects
				(font
					(size 0.7 0.7)
					(thickness 0.15)
				)
				(justify left bottom)
			)
		)
		(pad "1" smd custom
			(at -2.71 0 270)
			(size 6 0.575)
			(layers "F.Cu" "F.Paste" "F.Mask")
			(net 2 "+12V")
			(pintype "passive")
			(options
				(clearance outline)
				(anchor rect)
			)
			(primitives
				(gr_poly
					(pts
						(xy 2.4 1.71) (xy 2.117646 1.21) (xy 1.9 0.96) (xy 1.65 0.71) (xy 1.2 0.41) (xy 0.4 0.11) (xy 0.4 0.01)
						(xy 2.9 0) (xy 2.9 1.71)
					)
					(width 0.2)
					(fill yes)
				)
				(gr_poly
					(pts
						(xy -2.4 1.731128) (xy -2.117646 1.231128) (xy -1.9 0.981128) (xy -1.65 0.731128) (xy -1.2 0.431128)
						(xy -0.4 0.131128) (xy -0.4 0.031128) (xy -2.9 0.021128) (xy -2.9 1.731128)
					)
					(width 0.2)
					(fill yes)
				)
			)
		)
		(pad "2" smd custom
			(at 2.71 0 90)
			(size 6 0.575)
			(layers "F.Cu" "F.Paste" "F.Mask")
			(net 58 "Net-(L3-Pad2)")
			(pintype "passive")
			(options
				(clearance outline)
				(anchor rect)
			)
			(primitives
				(gr_poly
					(pts
						(xy -2.4 1.731128) (xy -2.117646 1.231128) (xy -1.9 0.981128) (xy -1.65 0.731128) (xy -1.2 0.431128)
						(xy -0.4 0.131128) (xy -0.4 0.031128) (xy -2.9 0.021128) (xy -2.9 1.731128)
					)
					(width 0.2)
					(fill yes)
				)
				(gr_poly
					(pts
						(xy 2.4 1.71) (xy 2.117646 1.21) (xy 1.9 0.96) (xy 1.65 0.71) (xy 1.2 0.41) (xy 0.4 0.11) (xy 0.4 0.01)
						(xy 2.9 0) (xy 2.9 1.71)
					)
					(width 0.2)
					(fill yes)
				)
			)
		)
	)
	(footprint "antmicro-footprints:C_0402_1005Metric"
		(layer "F.Cu")
		(at 146.72 97.36 -45)
		(descr "Capacitor SMD 0402")
		(tags "capacitor SMD 0402")
		(property "Reference" "C32"
			(at 0.59397 -2.545584 -45)
			(unlocked yes)
			(layer "F.SilkS")
			(effects
				(font
					(size 0.7 0.7)
					(thickness 0.15)
				)
				(justify right bottom)
			)
		)
		(property "Value" "C_10n_0402"
			(at -1.022927 2.155213 135)
			(layer "F.Fab")
			(effects
				(font
					(size 0.7 0.7)
					(thickness 0.15)
				)
				(justify right bottom)
			)
		)
		(property "Footprint" "antmicro-footprints:C_0402_1005Metric"
			(at 0 0 -45)
			(layer "F.Fab")
			(hide yes)
			(effects
				(font
					(size 1.27 1.27)
					(thickness 0.15)
				)
			)
		)
		(property "Datasheet" "https://www.murata.com/products/productdetail?partno=GRM155R71H103KA88%23"
			(at 0 0 -45)
			(layer "F.Fab")
			(hide yes)
			(effects
				(font
					(size 1.27 1.27)
					(thickness 0.15)
				)
			)
		)
		(property "Author" "Antmicro"
			(at -25.870623 132.26279 0)
			(layer "F.Fab")
			(hide yes)
			(effects
				(font
					(size 1 1)
					(thickness 0.15)
				)
			)
		)
		(property "Dielectric" "X7R"
			(at -25.870623 132.26279 0)
			(layer "F.Fab")
			(hide yes)
			(effects
				(font
					(size 1 1)
					(thickness 0.15)
				)
			)
		)
		(property "License" "Apache-2.0"
			(at -25.870623 132.26279 0)
			(layer "F.Fab")
			(hide yes)
			(effects
				(font
					(size 1 1)
					(thickness 0.15)
				)
			)
		)
		(property "MPN" "GRM155R71H103KA88D"
			(at -25.870623 132.26279 0)
			(layer "F.Fab")
			(hide yes)
			(effects
				(font
					(size 1 1)
					(thickness 0.15)
				)
			)
		)
		(property "Manufacturer" "Murata"
			(at -25.870623 132.26279 0)
			(layer "F.Fab")
			(hide yes)
			(effects
				(font
					(size 1 1)
					(thickness 0.15)
				)
			)
		)
		(property "Val" "10n"
			(at -25.870623 132.26279 0)
			(layer "F.Fab")
			(hide yes)
			(effects
				(font
					(size 1 1)
					(thickness 0.15)
				)
			)
		)
		(property "Voltage" "50V"
			(at -25.870623 132.26279 0)
			(layer "F.Fab")
			(hide yes)
			(effects
				(font
					(size 1 1)
					(thickness 0.15)
				)
			)
		)
		(sheetname "Serializer")
		(sheetfile "serializer.kicad_sch")
		(attr smd)
		(fp_poly
			(pts
				(xy -0.925 -0.47) (xy 0.925 -0.47) (xy 0.925 0.47) (xy -0.925 0.47)
			)
			(stroke
				(width 0.05)
				(type default)
			)
			(fill none)
			(layer "F.CrtYd")
		)
		(fp_line
			(start -0.494 0.248)
			(end -0.494 -0.25)
			(stroke
				(width 0.15)
				(type solid)
			)
			(layer "F.Fab")
		)
		(fp_line
			(start -0.494 -0.25)
			(end 0.504 -0.25)
			(stroke
				(width 0.15)
				(type solid)
			)
			(layer "F.Fab")
		)
		(fp_line
			(start 0.504 0.248)
			(end -0.494 0.248)
			(stroke
				(width 0.15)
				(type solid)
			)
			(layer "F.Fab")
		)
		(fp_line
			(start 0.504 -0.25)
			(end 0.504 0.248)
			(stroke
				(width 0.15)
				(type solid)
			)
			(layer "F.Fab")
		)
		(fp_text user "License: Apache-2.0"
			(at -0.939 5.799 135)
			(layer "F.Fab")
			(hide yes)
			(effects
				(font
					(size 0.7 0.7)
					(thickness 0.15)
				)
				(justify right bottom)
			)
		)
		(fp_text user "Author: Antmicro"
			(at -0.939 3.399 135)
			(layer "F.Fab")
			(hide yes)
			(effects
				(font
					(size 0.7 0.7)
					(thickness 0.15)
				)
				(justify right bottom)
			)
		)
		(fp_text user "${REFERENCE}"
			(at -0.939 4.599 135)
			(layer "F.Fab")
			(hide yes)
			(effects
				(font
					(size 0.7 0.7)
					(thickness 0.15)
				)
				(justify right bottom)
			)
		)
		(pad "1" smd roundrect
			(at -0.48 0 315)
			(size 0.59 0.64)
			(layers "F.Cu" "F.Paste" "F.Mask")
			(roundrect_rratio 0.25)
			(net 1 "GND")
			(pintype "passive")
		)
		(pad "2" smd roundrect
			(at 0.48 0 315)
			(size 0.59 0.64)
			(layers "F.Cu" "F.Paste" "F.Mask")
			(roundrect_rratio 0.25)
			(net 10 "+3V3")
			(pintype "passive")
		)
	)
	(footprint "antmicro-footprints:C_0402_1005Metric"
		(layer "F.Cu")
		(at 159.3 102.431 -90)
		(descr "Capacitor SMD 0402")
		(tags "capacitor SMD 0402")
		(property "Reference" "C4"
			(at -0.692 0.577 90)
			(layer "F.SilkS")
			(effects
				(font
					(size 0.7 0.7)
					(thickness 0.15)
				)
				(justify right bottom)
			)
		)
		(property "Value" "C_100n_0402"
			(at -1.022927 2.155213 90)
			(layer "F.Fab")
			(effects
				(font
					(size 0.7 0.7)
					(thickness 0.15)
				)
				(justify right bottom)
			)
		)
		(property "Footprint" "antmicro-footprints:C_0402_1005Metric"
			(at 0 0 -90)
			(layer "F.Fab")
			(hide yes)
			(effects
				(font
					(size 1.27 1.27)
					(thickness 0.15)
				)
			)
		)
		(property "Datasheet" "https://www.murata.com/products/productdetail?partno=GRM155R61H104KE14%23"
			(at 0 0 -90)
			(layer "F.Fab")
			(hide yes)
			(effects
				(font
					(size 1.27 1.27)
					(thickness 0.15)
				)
			)
		)
		(property "Author" "Antmicro"
			(at 56.869 261.731 0)
			(layer "F.Fab")
			(hide yes)
			(effects
				(font
					(size 1 1)
					(thickness 0.15)
				)
			)
		)
		(property "Dielectric" "X5R"
			(at 56.869 261.731 0)
			(layer "F.Fab")
			(hide yes)
			(effects
				(font
					(size 1 1)
					(thickness 0.15)
				)
			)
		)
		(property "License" "Apache-2.0"
			(at 56.869 261.731 0)
			(layer "F.Fab")
			(hide yes)
			(effects
				(font
					(size 1 1)
					(thickness 0.15)
				)
			)
		)
		(property "MPN" "GRM155R61H104KE14D"
			(at 56.869 261.731 0)
			(layer "F.Fab")
			(hide yes)
			(effects
				(font
					(size 1 1)
					(thickness 0.15)
				)
			)
		)
		(property "Manufacturer" "Murata"
			(at 56.869 261.731 0)
			(layer "F.Fab")
			(hide yes)
			(effects
				(font
					(size 1 1)
					(thickness 0.15)
				)
			)
		)
		(property "Val" "100n"
			(at 56.869 261.731 0)
			(layer "F.Fab")
			(hide yes)
			(effects
				(font
					(size 1 1)
					(thickness 0.15)
				)
			)
		)
		(property "Voltage" "50V"
			(at 56.869 261.731 0)
			(layer "F.Fab")
			(hide yes)
			(effects
				(font
					(size 1 1)
					(thickness 0.15)
				)
			)
		)
		(sheetname "Supply")
		(sheetfile "supply.kicad_sch")
		(attr smd)
		(fp_rect
			(start -0.925 -0.47)
			(end 0.925 0.47)
			(stroke
				(width 0.05)
				(type default)
			)
			(fill none)
			(layer "F.CrtYd")
		)
		(fp_line
			(start -0.494 0.248)
			(end -0.494 -0.25)
			(stroke
				(width 0.15)
				(type solid)
			)
			(layer "F.Fab")
		)
		(fp_line
			(start 0.504 0.248)
			(end -0.494 0.248)
			(stroke
				(width 0.15)
				(type solid)
			)
			(layer "F.Fab")
		)
		(fp_line
			(start -0.494 -0.25)
			(end 0.504 -0.25)
			(stroke
				(width 0.15)
				(type solid)
			)
			(layer "F.Fab")
		)
		(fp_line
			(start 0.504 -0.25)
			(end 0.504 0.248)
			(stroke
				(width 0.15)
				(type solid)
			)
			(layer "F.Fab")
		)
		(fp_text user "Author: Antmicro"
			(at -0.939 3.399 90)
			(layer "F.Fab")
			(hide yes)
			(effects
				(font
					(size 0.7 0.7)
					(thickness 0.15)
				)
				(justify right bottom)
			)
		)
		(fp_text user "${REFERENCE}"
			(at -0.939 4.599 90)
			(layer "F.Fab")
			(hide yes)
			(effects
				(font
					(size 0.7 0.7)
					(thickness 0.15)
				)
				(justify right bottom)
			)
		)
		(fp_text user "License: Apache-2.0"
			(at -0.939 5.799 90)
			(layer "F.Fab")
			(hide yes)
			(effects
				(font
					(size 0.7 0.7)
					(thickness 0.15)
				)
				(justify right bottom)
			)
		)
		(pad "1" smd roundrect
			(at -0.48 0 270)
			(size 0.59 0.64)
			(layers "F.Cu" "F.Paste" "F.Mask")
			(roundrect_rratio 0.25)
			(net 5 "Net-(U2-BST)")
			(pintype "passive")
		)
		(pad "2" smd roundrect
			(at 0.48 0 270)
			(size 0.59 0.64)
			(layers "F.Cu" "F.Paste" "F.Mask")
			(roundrect_rratio 0.25)
			(net 6 "/Supply/SW_1V8")
			(pintype "passive")
		)
	)
	(footprint "antmicro-footprints:R_0402_1005Metric"
		(layer "F.Cu")
		(at 133.1 110.95)
		(descr "Resistor SMD 0402")
		(tags "resistor SMD 0402")
		(property "Reference" "R25"
			(at 1.05 -5.558334 0)
			(layer "F.SilkS")
			(effects
				(font
					(size 0.7 0.7)
					(thickness 0.15)
				)
				(justify left bottom)
			)
		)
		(property "Value" "R_100R_0402"
			(at -1.011843 1.772047 0)
			(layer "F.Fab")
			(effects
				(font
					(size 0.7 0.7)
					(thickness 0.15)
				)
				(justify left bottom)
			)
		)
		(property "Footprint" "antmicro-footprints:R_0402_1005Metric"
			(at 0 0 0)
			(layer "F.Fab")
			(hide yes)
			(effects
				(font
					(size 1.27 1.27)
					(thickness 0.15)
				)
			)
		)
		(property "Datasheet" "https://www.bourns.com/docs/product-datasheets/cr.pdf"
			(at 0 0 0)
			(layer "F.Fab")
			(hide yes)
			(effects
				(font
					(size 1.27 1.27)
					(thickness 0.15)
				)
			)
		)
		(property "Author" "Antmicro"
			(at 0 0 0)
			(layer "F.Fab")
			(hide yes)
			(effects
				(font
					(size 1 1)
					(thickness 0.15)
				)
			)
		)
		(property "License" "Apache-2.0"
			(at 0 0 0)
			(layer "F.Fab")
			(hide yes)
			(effects
				(font
					(size 1 1)
					(thickness 0.15)
				)
			)
		)
		(property "MPN" "CR0402-FX-1000GLF"
			(at 0 0 0)
			(layer "F.Fab")
			(hide yes)
			(effects
				(font
					(size 1 1)
					(thickness 0.15)
				)
			)
		)
		(property "Manufacturer" "Bourns"
			(at 0 0 0)
			(layer "F.Fab")
			(hide yes)
			(effects
				(font
					(size 1 1)
					(thickness 0.15)
				)
			)
		)
		(property "Tolerance" "1%"
			(at 0 0 0)
			(layer "F.Fab")
			(hide yes)
			(effects
				(font
					(size 1 1)
					(thickness 0.15)
				)
			)
		)
		(property "Val" "100R"
			(at 0 0 0)
			(layer "F.Fab")
			(hide yes)
			(effects
				(font
					(size 1 1)
					(thickness 0.15)
				)
			)
		)
		(sheetname "CSI Connector")
		(sheetfile "CSI.kicad_sch")
		(attr smd)
		(fp_rect
			(start -0.925 -0.47)
			(end 0.925 0.47)
			(stroke
				(width 0.05)
				(type default)
			)
			(fill none)
			(layer "F.CrtYd")
		)
		(fp_rect
			(start -0.5 -0.25)
			(end 0.5 0.25)
			(stroke
				(width 0.15)
				(type solid)
			)
			(fill none)
			(layer "F.Fab")
		)
		(fp_text user "License: Apache-2.0"
			(at -0.95 5.169 0)
			(layer "F.Fab")
			(hide yes)
			(effects
				(font
					(size 0.7 0.7)
					(thickness 0.15)
				)
				(justify left bottom)
			)
		)
		(fp_text user "Author: Antmicro"
			(at -0.95 4.169 0)
			(layer "F.Fab")
			(hide yes)
			(effects
				(font
					(size 0.7 0.7)
					(thickness 0.15)
				)
				(justify left bottom)
			)
		)
		(fp_text user "${REFERENCE}"
			(at -0.95 3.168 0)
			(layer "F.Fab")
			(hide yes)
			(effects
				(font
					(size 0.7 0.7)
					(thickness 0.15)
				)
				(justify left bottom)
			)
		)
		(pad "1" smd roundrect
			(at -0.48 0)
			(size 0.59 0.64)
			(layers "F.Cu" "F.Paste" "F.Mask")
			(roundrect_rratio 0.25)
			(net 37 "/CSI Connector/SCL_CAM1")
			(pintype "passive")
		)
		(pad "2" smd roundrect
			(at 0.48 0)
			(size 0.59 0.64)
			(layers "F.Cu" "F.Paste" "F.Mask")
			(roundrect_rratio 0.25)
			(net 89 "/CSI Connector/I2C.SCL")
			(pintype "passive")
		)
	)
)
